(kicad_pcb
	(version 20241229)
	(generator "pcbnew")
	(generator_version "9.0")
	(general
		(thickness 1.63)
		(legacy_teardrops no)
	)
	(paper "A4")
	(title_block
		(title "CM4 Baseboard")
		(date "2026-01-05")
		(rev "1.1.1")
		(company "Antmicro Ltd")
		(comment 1 "www.antmicro.com")
		(comment 9 "footprints 339-343 of 506")
	)
	(layers
		(0 "F.Cu" signal)
		(4 "In1.Cu" power)
		(6 "In2.Cu" power)
		(8 "In3.Cu" signal)
		(10 "In4.Cu" signal)
		(2 "B.Cu" signal)
		(9 "F.Adhes" user "F.Adhesive")
		(11 "B.Adhes" user "B.Adhesive")
		(13 "F.Paste" user)
		(15 "B.Paste" user)
		(5 "F.SilkS" user "F.Silkscreen")
		(7 "B.SilkS" user "B.Silkscreen")
		(1 "F.Mask" user)
		(3 "B.Mask" user)
		(17 "Dwgs.User" user "User.Drawings")
		(19 "Cmts.User" user "User.Comments")
		(21 "Eco1.User" user "User.Eco1")
		(23 "Eco2.User" user "User.Eco2")
		(25 "Edge.Cuts" user)
		(27 "Margin" user)
		(31 "F.CrtYd" user "F.Courtyard")
		(29 "B.CrtYd" user "B.Courtyard")
		(35 "F.Fab" user)
		(33 "B.Fab" user)
	)
	(footprint "antmicro-footprints:R_0402_1005Metric"
		(layer "B.Cu")
		(at 52.842962 159.3915)
		(descr "Resistor SMD 0402")
		(tags "resistor SMD 0402")
		(property "Reference" "R316"
			(at -4.215 0.955 0)
			(layer "B.SilkS")
			(effects
				(font
					(size 0.7 0.7)
					(thickness 0.15)
				)
				(justify right bottom mirror)
			)
		)
		(property "Value" "R_15k_0402"
			(at -1.011843 -1.772047 0)
			(layer "B.Fab")
			(effects
				(font
					(size 0.7 0.7)
					(thickness 0.15)
				)
				(justify right bottom mirror)
			)
		)
		(property "Datasheet" "https://www.bourns.com/docs/product-datasheets/cr.pdf"
			(at 0 0 0)
			(layer "B.Fab")
			(hide yes)
			(effects
				(font
					(size 1.27 1.27)
					(thickness 0.15)
				)
			)
		)
		(property "Manufacturer" "Bourns"
			(at 0 0 0)
			(unlocked yes)
			(layer "B.Fab")
			(hide yes)
			(effects
				(font
					(size 1 1)
					(thickness 0.15)
				)
				(justify mirror)
			)
		)
		(property "MPN" "CR0402-FX-1502GLF"
			(at 0 0 0)
			(unlocked yes)
			(layer "B.Fab")
			(hide yes)
			(effects
				(font
					(size 1 1)
					(thickness 0.15)
				)
				(justify mirror)
			)
		)
		(property "Val" "15k"
			(at 0 0 0)
			(unlocked yes)
			(layer "B.Fab")
			(hide yes)
			(effects
				(font
					(size 1 1)
					(thickness 0.15)
				)
				(justify mirror)
			)
		)
		(property "License" "Apache-2.0"
			(at 0 0 0)
			(unlocked yes)
			(layer "B.Fab")
			(hide yes)
			(effects
				(font
					(size 1 1)
					(thickness 0.15)
				)
				(justify mirror)
			)
		)
		(property "Author" "Antmicro"
			(at 0 0 0)
			(unlocked yes)
			(layer "B.Fab")
			(hide yes)
			(effects
				(font
					(size 1 1)
					(thickness 0.15)
				)
				(justify mirror)
			)
		)
		(property "Tolerance" "1%"
			(at 0 0 0)
			(unlocked yes)
			(layer "B.Fab")
			(hide yes)
			(effects
				(font
					(size 1 1)
					(thickness 0.15)
				)
				(justify mirror)
			)
		)
		(sheetname "/Supply/")
		(sheetfile "supply.kicad_sch")
		(attr smd)
		(fp_rect
			(start -0.925 0.47)
			(end 0.925 -0.47)
			(stroke
				(width 0.05)
				(type default)
			)
			(fill no)
			(layer "B.CrtYd")
		)
		(fp_rect
			(start -0.5 0.25)
			(end 0.5 -0.25)
			(stroke
				(width 0.15)
				(type solid)
			)
			(fill no)
			(layer "B.Fab")
		)
		(fp_text user "Author: Antmicro"
			(at -0.95 -4.169 180)
			(layer "B.Fab")
			(effects
				(font
					(size 0.7 0.7)
					(thickness 0.15)
				)
				(justify left bottom mirror)
			)
		)
		(fp_text user "${REFERENCE}"
			(at -0.95 -3.168 180)
			(layer "B.Fab")
			(effects
				(font
					(size 0.7 0.7)
					(thickness 0.15)
				)
				(justify left bottom mirror)
			)
		)
		(fp_text user "License: Apache-2.0"
			(at -0.95 -5.169 180)
			(layer "B.Fab")
			(effects
				(font
					(size 0.7 0.7)
					(thickness 0.15)
				)
				(justify left bottom mirror)
			)
		)
		(pad "1" smd roundrect
			(at -0.48 0)
			(size 0.59 0.64)
			(layers "B.Cu" "B.Mask" "B.Paste")
			(roundrect_rratio 0.25)
			(net 353 "/Supply/FB_5V")
			(pintype "passive")
		)
		(pad "2" smd roundrect
			(at 0.48 0)
			(size 0.59 0.64)
			(layers "B.Cu" "B.Mask" "B.Paste")
			(roundrect_rratio 0.25)
			(net 77 "/Supply/OUT_5V")
			(pintype "passive")
		)
	)
	(footprint "antmicro-footprints:SOD-523"
		(layer "B.Cu")
		(at 113.592962 119.4665 180)
		(property "Reference" "D712"
			(at -2.245 -5.65 0)
			(layer "B.SilkS")
			(effects
				(font
					(size 0.7 0.7)
					(thickness 0.15)
				)
				(justify left bottom mirror)
			)
		)
		(property "Value" "PESD5Z5_0F"
			(at 0 -1.499 0)
			(layer "B.Fab")
			(effects
				(font
					(size 0.7 0.7)
					(thickness 0.15)
				)
				(justify left bottom mirror)
			)
		)
		(property "Datasheet" "https://assets.nexperia.com/documents/data-sheet/PESD5Z5_0.pdf"
			(at 0 0 180)
			(layer "B.Fab")
			(hide yes)
			(effects
				(font
					(size 1.27 1.27)
					(thickness 0.15)
				)
			)
		)
		(property "Manufacturer" "Nexperia"
			(at 0 0 180)
			(unlocked yes)
			(layer "B.Fab")
			(hide yes)
			(effects
				(font
					(size 1 1)
					(thickness 0.15)
				)
				(justify mirror)
			)
		)
		(property "MPN" "PESD5Z5.0F"
			(at 0 0 180)
			(unlocked yes)
			(layer "B.Fab")
			(hide yes)
			(effects
				(font
					(size 1 1)
					(thickness 0.15)
				)
				(justify mirror)
			)
		)
		(property "Author" "Antmicro"
			(at 0 0 180)
			(unlocked yes)
			(layer "B.Fab")
			(hide yes)
			(effects
				(font
					(size 1 1)
					(thickness 0.15)
				)
				(justify mirror)
			)
		)
		(property "License" "Apache-2.0"
			(at 0 0 180)
			(unlocked yes)
			(layer "B.Fab")
			(hide yes)
			(effects
				(font
					(size 1 1)
					(thickness 0.15)
				)
				(justify mirror)
			)
		)
		(sheetname "/Display/")
		(sheetfile "display.kicad_sch")
		(attr smd)
		(fp_line
			(start -0.35 0.5)
			(end -0.35 -0.5)
			(stroke
				(width 0.15)
				(type solid)
			)
			(layer "B.SilkS")
		)
		(fp_rect
			(start -1 0.6)
			(end 1 -0.6)
			(stroke
				(width 0.05)
				(type solid)
			)
			(fill no)
			(layer "B.CrtYd")
		)
		(fp_line
			(start 0.65 0.425)
			(end 0.65 -0.423)
			(stroke
				(width 0.15)
				(type solid)
			)
			(layer "B.Fab")
		)
		(fp_line
			(start -0.35 0.4)
			(end -0.35 -0.4)
			(stroke
				(width 0.15)
				(type solid)
			)
			(layer "B.Fab")
		)
		(fp_line
			(start -0.652 0.425)
			(end 0.65 0.425)
			(stroke
				(width 0.15)
				(type solid)
			)
			(layer "B.Fab")
		)
		(fp_line
			(start -0.652 -0.423)
			(end 0.65 -0.423)
			(stroke
				(width 0.15)
				(type solid)
			)
			(layer "B.Fab")
		)
		(fp_line
			(start -0.652 -0.423)
			(end -0.652 0.425)
			(stroke
				(width 0.15)
				(type solid)
			)
			(layer "B.Fab")
		)
		(fp_text user "${REFERENCE}"
			(at -1.276 -3.499 0)
			(layer "B.Fab")
			(effects
				(font
					(size 0.7 0.7)
					(thickness 0.15)
				)
				(justify left bottom mirror)
			)
		)
		(fp_text user "Author: Antmicro"
			(at -1.276 -4.7 0)
			(layer "B.Fab")
			(effects
				(font
					(size 0.7 0.7)
					(thickness 0.15)
				)
				(justify left bottom mirror)
			)
		)
		(fp_text user "License: Apache-2.0"
			(at -1.276 -5.9 0)
			(layer "B.Fab")
			(effects
				(font
					(size 0.7 0.7)
					(thickness 0.15)
				)
				(justify left bottom mirror)
			)
		)
		(pad "1" smd roundrect
			(at -0.701 0 180)
			(size 0.5 0.6)
			(layers "B.Cu" "B.Mask" "B.Paste")
			(roundrect_rratio 0.25)
			(net 119 "Net-(D710-C)")
			(pinfunction "C")
			(pintype "passive")
		)
		(pad "2" smd roundrect
			(at 0.699 0 180)
			(size 0.5 0.6)
			(layers "B.Cu" "B.Mask" "B.Paste")
			(roundrect_rratio 0.25)
			(net 3 "GND")
			(pinfunction "A")
			(pintype "passive")
		)
	)
	(footprint "antmicro-footprints:C_0805_2012Metric"
		(layer "B.Cu")
		(at 50.742962 156.3665 -90)
		(descr "Capacitor SMD 0805")
		(tags "capacitor SMD 0805")
		(property "Reference" "C303"
			(at -5.09 0.875 90)
			(layer "B.SilkS")
			(effects
				(font
					(size 0.7 0.7)
					(thickness 0.15)
				)
				(justify left bottom mirror)
			)
		)
		(property "Value" "C_22u_25V_0805"
			(at -2.055717 -1.963152 90)
			(layer "B.Fab")
			(effects
				(font
					(size 0.7 0.7)
					(thickness 0.15)
				)
				(justify left bottom mirror)
			)
		)
		(property "Datasheet" "https://product.samsungsem.com/mlcc/CL21A226MAYNNN.do"
			(at 0 0 270)
			(layer "B.Fab")
			(hide yes)
			(effects
				(font
					(size 1.27 1.27)
					(thickness 0.15)
				)
			)
		)
		(property "Manufacturer" "Samsung Electro-Mechanics"
			(at 0 0 270)
			(unlocked yes)
			(layer "B.Fab")
			(hide yes)
			(effects
				(font
					(size 1 1)
					(thickness 0.15)
				)
				(justify mirror)
			)
		)
		(property "MPN" "CL21A226MAYNNNE"
			(at 0 0 270)
			(unlocked yes)
			(layer "B.Fab")
			(hide yes)
			(effects
				(font
					(size 1 1)
					(thickness 0.15)
				)
				(justify mirror)
			)
		)
		(property "Val" "22u"
			(at 0 0 270)
			(unlocked yes)
			(layer "B.Fab")
			(hide yes)
			(effects
				(font
					(size 1 1)
					(thickness 0.15)
				)
				(justify mirror)
			)
		)
		(property "License" "Apache-2.0"
			(at 0 0 270)
			(unlocked yes)
			(layer "B.Fab")
			(hide yes)
			(effects
				(font
					(size 1 1)
					(thickness 0.15)
				)
				(justify mirror)
			)
		)
		(property "Author" "Antmicro"
			(at 0 0 270)
			(unlocked yes)
			(layer "B.Fab")
			(hide yes)
			(effects
				(font
					(size 1 1)
					(thickness 0.15)
				)
				(justify mirror)
			)
		)
		(property "Voltage" "25V"
			(at 0 0 270)
			(unlocked yes)
			(layer "B.Fab")
			(hide yes)
			(effects
				(font
					(size 1 1)
					(thickness 0.15)
				)
				(justify mirror)
			)
		)
		(property "Dielectric" "X5R"
			(at 0 0 270)
			(unlocked yes)
			(layer "B.Fab")
			(hide yes)
			(effects
				(font
					(size 1 1)
					(thickness 0.15)
				)
				(justify mirror)
			)
		)
		(property "Public" "False"
			(at 0 0 270)
			(unlocked yes)
			(layer "B.Fab")
			(hide yes)
			(effects
				(font
					(size 1 1)
					(thickness 0.15)
				)
				(justify mirror)
			)
		)
		(sheetname "/Supply/")
		(sheetfile "supply.kicad_sch")
		(attr smd)
		(fp_line
			(start -0.3 0.7)
			(end 0.3 0.7)
			(stroke
				(width 0.15)
				(type solid)
			)
			(layer "B.SilkS")
		)
		(fp_line
			(start -0.3 -0.7)
			(end 0.3 -0.7)
			(stroke
				(width 0.15)
				(type solid)
			)
			(layer "B.SilkS")
		)
		(fp_rect
			(start 1.95 0.9)
			(end -1.95 -0.9)
			(stroke
				(width 0.05)
				(type default)
			)
			(fill no)
			(layer "B.CrtYd")
		)
		(fp_rect
			(start -0.95 0.675)
			(end 0.95 -0.675)
			(stroke
				(width 0.15)
				(type solid)
			)
			(fill no)
			(layer "B.Fab")
		)
		(fp_text user "${REFERENCE}"
			(at -1.9 -3.947 90)
			(layer "B.Fab")
			(effects
				(font
					(size 0.7 0.7)
					(thickness 0.15)
				)
				(justify left bottom mirror)
			)
		)
		(fp_text user "License: Apache-2.0"
			(at -1.9 -4.947 90)
			(layer "B.Fab")
			(effects
				(font
					(size 0.7 0.7)
					(thickness 0.15)
				)
				(justify left bottom mirror)
			)
		)
		(fp_text user "Author: Antmicro"
			(at -1.9 -5.947 90)
			(layer "B.Fab")
			(effects
				(font
					(size 0.7 0.7)
					(thickness 0.15)
				)
				(justify left bottom mirror)
			)
		)
		(pad "1" smd roundrect
			(at -1.1 0 270)
			(size 1.2 1.3)
			(layers "B.Cu" "B.Mask" "B.Paste")
			(roundrect_rratio 0.25)
			(net 43 "VCC")
			(pintype "passive")
		)
		(pad "2" smd roundrect
			(at 1.1 0 270)
			(size 1.2 1.3)
			(layers "B.Cu" "B.Mask" "B.Paste")
			(roundrect_rratio 0.25)
			(net 3 "GND")
			(pintype "passive")
		)
	)
	(footprint "antmicro-footprints:R_0603_1608Metric"
		(layer "B.Cu")
		(at 74.317962 165.8915)
		(descr "Resistor SMD 0603")
		(tags "resistor SMD 0603")
		(property "Reference" "R323"
			(at -1.45 1.505 0)
			(layer "B.SilkS")
			(effects
				(font
					(size 0.7 0.7)
					(thickness 0.15)
				)
				(justify right bottom mirror)
			)
		)
		(property "Value" "R_0R_22.4A_0603"
			(at 0 -1.6 0)
			(layer "B.Fab")
			(effects
				(font
					(size 0.7 0.7)
					(thickness 0.15)
				)
				(justify right bottom mirror)
			)
		)
		(property "Datasheet" "https://fscdn.rohm.com/en/products/databook/datasheet/passive/resistor/chip_resistor/pmr-jpw-e.pdf"
			(at 0 0 0)
			(layer "B.Fab")
			(hide yes)
			(effects
				(font
					(size 1.27 1.27)
					(thickness 0.15)
				)
			)
		)
		(property "Manufacturer" "ROHM Semiconductor"
			(at 0 0 0)
			(unlocked yes)
			(layer "B.Fab")
			(hide yes)
			(effects
				(font
					(size 1 1)
					(thickness 0.15)
				)
				(justify mirror)
			)
		)
		(property "MPN" "PMR03EZPJ000"
			(at 0 0 0)
			(unlocked yes)
			(layer "B.Fab")
			(hide yes)
			(effects
				(font
					(size 1 1)
					(thickness 0.15)
				)
				(justify mirror)
			)
		)
		(property "Val" "0R"
			(at 0 0 0)
			(unlocked yes)
			(layer "B.Fab")
			(hide yes)
			(effects
				(font
					(size 1 1)
					(thickness 0.15)
				)
				(justify mirror)
			)
		)
		(property "Author" "Antmicro"
			(at 0 0 0)
			(unlocked yes)
			(layer "B.Fab")
			(hide yes)
			(effects
				(font
					(size 1 1)
					(thickness 0.15)
				)
				(justify mirror)
			)
		)
		(property "License" "Apache-2.0"
			(at 0 0 0)
			(unlocked yes)
			(layer "B.Fab")
			(hide yes)
			(effects
				(font
					(size 1 1)
					(thickness 0.15)
				)
				(justify mirror)
			)
		)
		(property "Max. Curr." "22.4A"
			(at 0 0 0)
			(unlocked yes)
			(layer "B.Fab")
			(hide yes)
			(effects
				(font
					(size 1 1)
					(thickness 0.15)
				)
				(justify mirror)
			)
		)
		(property "Tolerance" "template_tolerance"
			(at 0 0 0)
			(unlocked yes)
			(layer "B.Fab")
			(hide yes)
			(effects
				(font
					(size 1 1)
					(thickness 0.15)
				)
				(justify mirror)
			)
		)
		(sheetname "/Supply/")
		(sheetfile "supply.kicad_sch")
		(attr smd)
		(fp_line
			(start -0.15 -0.4)
			(end 0.15 -0.4)
			(stroke
				(width 0.15)
				(type solid)
			)
			(layer "B.SilkS")
		)
		(fp_line
			(start -0.15 0.4)
			(end 0.15 0.4)
			(stroke
				(width 0.15)
				(type solid)
			)
			(layer "B.SilkS")
		)
		(fp_rect
			(start -1.25 0.65)
			(end 1.25 -0.65)
			(stroke
				(width 0.05)
				(type solid)
			)
			(fill no)
			(layer "B.CrtYd")
		)
		(fp_rect
			(start -0.8 0.4)
			(end 0.8 -0.4)
			(stroke
				(width 0.15)
				(type solid)
			)
			(fill no)
			(layer "B.Fab")
		)
		(fp_text user "Author: Antmicro"
			(at -1.25 -4.9 180)
			(layer "B.Fab")
			(effects
				(font
					(size 0.7 0.7)
					(thickness 0.15)
				)
				(justify left bottom mirror)
			)
		)
		(fp_text user "${REFERENCE}"
			(at -1.25 -3.898 180)
			(layer "B.Fab")
			(effects
				(font
					(size 0.7 0.7)
					(thickness 0.15)
				)
				(justify left bottom mirror)
			)
		)
		(fp_text user "License: Apache-2.0"
			(at -1.25 -5.9 180)
			(layer "B.Fab")
			(effects
				(font
					(size 0.7 0.7)
					(thickness 0.15)
				)
				(justify left bottom mirror)
			)
		)
		(pad "1" smd roundrect
			(at -0.7 0)
			(size 0.8 1)
			(layers "B.Cu" "B.Mask" "B.Paste")
			(roundrect_rratio 0.2)
			(net 89 "/Supply/OUT_3V3")
			(pintype "passive")
		)
		(pad "2" smd roundrect
			(at 0.7 0)
			(size 0.8 1)
			(layers "B.Cu" "B.Mask" "B.Paste")
			(roundrect_rratio 0.2)
			(net 9 "+3V3")
			(pintype "passive")
		)
	)
	(footprint "antmicro-footprints:C_0805_2012Metric"
		(layer "B.Cu")
		(at 72.117962 164.8415 90)
		(descr "Capacitor SMD 0805")
		(tags "capacitor SMD 0805")
		(property "Reference" "C317"
			(at -4.525 0.51 90)
			(layer "B.SilkS")
			(effects
				(font
					(size 0.7 0.7)
					(thickness 0.15)
				)
				(justify right bottom mirror)
			)
		)
		(property "Value" "C_22u_25V_0805"
			(at -2.055717 -1.963152 90)
			(layer "B.Fab")
			(effects
				(font
					(size 0.7 0.7)
					(thickness 0.15)
				)
				(justify right bottom mirror)
			)
		)
		(property "Datasheet" "https://product.samsungsem.com/mlcc/CL21A226MAYNNN.do"
			(at 0 0 90)
			(layer "B.Fab")
			(hide yes)
			(effects
				(font
					(size 1.27 1.27)
					(thickness 0.15)
				)
			)
		)
		(property "Manufacturer" "Samsung Electro-Mechanics"
			(at 0 0 90)
			(unlocked yes)
			(layer "B.Fab")
			(hide yes)
			(effects
				(font
					(size 1 1)
					(thickness 0.15)
				)
				(justify mirror)
			)
		)
		(property "MPN" "CL21A226MAYNNNE"
			(at 0 0 90)
			(unlocked yes)
			(layer "B.Fab")
			(hide yes)
			(effects
				(font
					(size 1 1)
					(thickness 0.15)
				)
				(justify mirror)
			)
		)
		(property "Val" "22u"
			(at 0 0 90)
			(unlocked yes)
			(layer "B.Fab")
			(hide yes)
			(effects
				(font
					(size 1 1)
					(thickness 0.15)
				)
				(justify mirror)
			)
		)
		(property "License" "Apache-2.0"
			(at 0 0 90)
			(unlocked yes)
			(layer "B.Fab")
			(hide yes)
			(effects
				(font
					(size 1 1)
					(thickness 0.15)
				)
				(justify mirror)
			)
		)
		(property "Author" "Antmicro"
			(at 0 0 90)
			(unlocked yes)
			(layer "B.Fab")
			(hide yes)
			(effects
				(font
					(size 1 1)
					(thickness 0.15)
				)
				(justify mirror)
			)
		)
		(property "Voltage" "25V"
			(at 0 0 90)
			(unlocked yes)
			(layer "B.Fab")
			(hide yes)
			(effects
				(font
					(size 1 1)
					(thickness 0.15)
				)
				(justify mirror)
			)
		)
		(property "Dielectric" "X5R"
			(at 0 0 90)
			(unlocked yes)
			(layer "B.Fab")
			(hide yes)
			(effects
				(font
					(size 1 1)
					(thickness 0.15)
				)
				(justify mirror)
			)
		)
		(property "Public" "False"
			(at 0 0 90)
			(unlocked yes)
			(layer "B.Fab")
			(hide yes)
			(effects
				(font
					(size 1 1)
					(thickness 0.15)
				)
				(justify mirror)
			)
		)
		(sheetname "/Supply/")
		(sheetfile "supply.kicad_sch")
		(attr smd)
		(fp_line
			(start -0.3 -0.7)
			(end 0.3 -0.7)
			(stroke
				(width 0.15)
				(type solid)
			)
			(layer "B.SilkS")
		)
		(fp_line
			(start -0.3 0.7)
			(end 0.3 0.7)
			(stroke
				(width 0.15)
				(type solid)
			)
			(layer "B.SilkS")
		)
		(fp_rect
			(start 1.95 0.9)
			(end -1.95 -0.9)
			(stroke
				(width 0.05)
				(type default)
			)
			(fill no)
			(layer "B.CrtYd")
		)
		(fp_rect
			(start -0.95 0.675)
			(end 0.95 -0.675)
			(stroke
				(width 0.15)
				(type solid)
			)
			(fill no)
			(layer "B.Fab")
		)
		(fp_text user "${REFERENCE}"
			(at -1.9 -3.947 270)
			(layer "B.Fab")
			(effects
				(font
					(size 0.7 0.7)
					(thickness 0.15)
				)
				(justify left bottom mirror)
			)
		)
		(fp_text user "License: Apache-2.0"
			(at -1.9 -4.947 270)
			(layer "B.Fab")
			(effects
				(font
					(size 0.7 0.7)
					(thickness 0.15)
				)
				(justify left bottom mirror)
			)
		)
		(fp_text user "Author: Antmicro"
			(at -1.9 -5.947 270)
			(layer "B.Fab")
			(effects
				(font
					(size 0.7 0.7)
					(thickness 0.15)
				)
				(justify left bottom mirror)
			)
		)
		(pad "1" smd roundrect
			(at -1.1 0 90)
			(size 1.2 1.3)
			(layers "B.Cu" "B.Mask" "B.Paste")
			(roundrect_rratio 0.25)
			(net 89 "/Supply/OUT_3V3")
			(pintype "passive")
		)
		(pad "2" smd roundrect
			(at 1.1 0 90)
			(size 1.2 1.3)
			(layers "B.Cu" "B.Mask" "B.Paste")
			(roundrect_rratio 0.25)
			(net 3 "GND")
			(pintype "passive")
		)
	)
)
